(kicad_pcb
	(version 20260206)
	(generator "pcbnew")
	(generator_version "10.0")
	(general
		(thickness 1.6)
		(legacy_teardrops no)
	)
	(paper "A4")
	(title_block
		(title "baseboard — 13948-1b.1110WZS1818.brd")
		(comment 1 "Honey Badger (Wiwynn) / footprints 1079-1085 of 2523")
	)
	(layers
		(0 "F.Cu" signal "TOP")
		(4 "In1.Cu" signal "L2GND")
		(6 "In2.Cu" signal "L3")
		(8 "In3.Cu" signal "L4VCC")
		(10 "In4.Cu" signal "L5VCC")
		(12 "In5.Cu" signal "L6")
		(14 "In6.Cu" signal "L7GND")
		(2 "B.Cu" signal "BOTTOM")
		(9 "F.Adhes" user "F.Adhesive")
		(11 "B.Adhes" user "B.Adhesive")
		(13 "F.Paste" user "Package Geometry/Pastemask Top")
		(15 "B.Paste" user "Package Geometry/Pastemask Bottom")
		(5 "F.SilkS" user "Ref Des/Silkscreen Top")
		(7 "B.SilkS" user "Ref Des/Silkscreen Bottom")
		(1 "F.Mask" user "Board Geometry/Soldermask Top")
		(3 "B.Mask" user "Board Geometry/Soldermask Bottom")
		(17 "Dwgs.User" user "User.Drawings")
		(19 "Cmts.User" user "User.Comments")
		(21 "Eco1.User" user "User.Eco1")
		(23 "Eco2.User" user "User.Eco2")
		(25 "Edge.Cuts" user "Board Geometry/Outline")
		(27 "Margin" user)
		(31 "F.CrtYd" user "Package Geometry/Place Bound Top")
		(29 "B.CrtYd" user "Package Geometry/Place Bound Bottom")
		(35 "F.Fab" user "Ref Des/Assembly Top")
		(33 "B.Fab" user "Ref Des/Assembly Bottom")
	)
	(footprint ""
		(layer "F.Cu")
		(at 295.529 -161.544 180)
		(property "Reference" "R286"
			(at 0 0 180)
			(layer "F.SilkS")
			(hide yes)
			(effects
				(font
					(size 1.27 1.27)
				)
			)
		)
		(property "Value" "0R2J-2-GP"
			(at 0.064008 -3.993896 180)
			(unlocked yes)
			(layer "F.Fab")
			(hide yes)
			(effects
				(font
					(size 1.016 1.016)
					(thickness 0.1524)
				)
			)
		)
		(property "Device Type" "R402H16"
			(at 0.064008 -5.517896 180)
			(unlocked yes)
			(layer "F.Fab")
			(hide yes)
			(effects
				(font
					(size 1.016 1.016)
					(thickness 0.1524)
				)
			)
		)
		(duplicate_pad_numbers_are_jumpers no)
		(fp_line
			(start 0.508 -0.9398)
			(end -0.508 -0.9398)
			(stroke
				(width 0.1524)
				(type default)
			)
			(layer "F.SilkS")
		)
		(fp_line
			(start -0.508 -0.9398)
			(end -0.508 0.9398)
			(stroke
				(width 0.1524)
				(type default)
			)
			(layer "F.SilkS")
		)
		(fp_rect
			(start -0.508 0.9398)
			(end 0.508 -0.9398)
			(stroke
				(width 0)
				(type default)
			)
			(fill no)
			(layer "F.CrtYd")
		)
		(fp_rect
			(start -0.508 0.9398)
			(end 0.508 -0.9398)
			(stroke
				(width 0)
				(type default)
			)
			(fill no)
			(layer "F.Fab")
		)
		(pad "1" smd custom
			(at 0 -0.4445 180)
			(size 0.1397 0.1397)
			(layers "F.Cu" "F.Mask" "F.Paste")
			(net "RMII_BMC_CRS_DV")
			(options
				(clearance outline)
				(anchor circle)
			)
			(primitives
				(gr_poly
					(pts
						(arc
							(start -0.1778 -0.2794)
							(mid -0.249642 -0.249642)
							(end -0.2794 -0.1778)
						)
						(arc
							(start -0.2794 0.1778)
							(mid -0.249642 0.249642)
							(end -0.1778 0.2794)
						)
						(arc
							(start 0.1778 0.2794)
							(mid 0.249642 0.249642)
							(end 0.2794 0.1778)
						)
						(arc
							(start 0.2794 -0.1778)
							(mid 0.249642 -0.249642)
							(end 0.1778 -0.2794)
						)
					)
					(width 0)
					(fill yes)
				)
			)
		)
		(pad "2" smd custom
			(at 0 0.4445 180)
			(size 0.1397 0.1397)
			(layers "F.Cu" "F.Mask" "F.Paste")
			(net "RMII0_BMC_C_CRS_DV")
			(options
				(clearance outline)
				(anchor circle)
			)
			(primitives
				(gr_poly
					(pts
						(arc
							(start -0.1778 -0.2794)
							(mid -0.249642 -0.249642)
							(end -0.2794 -0.1778)
						)
						(arc
							(start -0.2794 0.1778)
							(mid -0.249642 0.249642)
							(end -0.1778 0.2794)
						)
						(arc
							(start 0.1778 0.2794)
							(mid 0.249642 0.249642)
							(end 0.2794 0.1778)
						)
						(arc
							(start 0.2794 -0.1778)
							(mid 0.249642 -0.249642)
							(end 0.1778 -0.2794)
						)
					)
					(width 0)
					(fill yes)
				)
			)
		)
	)
	(footprint ""
		(layer "F.Cu")
		(at 53.848 -224.917)
		(property "Reference" "R2107"
			(at 0 0 0)
			(layer "F.SilkS")
			(hide yes)
			(effects
				(font
					(size 1.27 1.27)
				)
			)
		)
		(property "Value" "49K9R2F-L-GP"
			(at 0.064008 -3.993896 0)
			(unlocked yes)
			(layer "F.Fab")
			(hide yes)
			(effects
				(font
					(size 1.016 1.016)
					(thickness 0.1524)
				)
			)
		)
		(property "Device Type" "R402H16"
			(at 0.064008 -5.517896 0)
			(unlocked yes)
			(layer "F.Fab")
			(hide yes)
			(effects
				(font
					(size 1.016 1.016)
					(thickness 0.1524)
				)
			)
		)
		(duplicate_pad_numbers_are_jumpers no)
		(fp_line
			(start -0.508 -0.9398)
			(end -0.508 0.9398)
			(stroke
				(width 0.1524)
				(type default)
			)
			(layer "F.SilkS")
		)
		(fp_line
			(start 0.508 -0.9398)
			(end -0.508 -0.9398)
			(stroke
				(width 0.1524)
				(type default)
			)
			(layer "F.SilkS")
		)
		(fp_rect
			(start -0.508 0.9398)
			(end 0.508 -0.9398)
			(stroke
				(width 0)
				(type default)
			)
			(fill no)
			(layer "F.CrtYd")
		)
		(fp_rect
			(start -0.508 0.9398)
			(end 0.508 -0.9398)
			(stroke
				(width 0)
				(type default)
			)
			(fill no)
			(layer "F.Fab")
		)
		(pad "1" smd custom
			(at 0 -0.4445)
			(size 0.1397 0.1397)
			(layers "F.Cu" "F.Mask" "F.Paste")
			(net "P12V_PCIE")
			(options
				(clearance outline)
				(anchor circle)
			)
			(primitives
				(gr_poly
					(pts
						(arc
							(start -0.1778 -0.2794)
							(mid -0.249642 -0.249642)
							(end -0.2794 -0.1778)
						)
						(arc
							(start -0.2794 0.1778)
							(mid -0.249642 0.249642)
							(end -0.1778 0.2794)
						)
						(arc
							(start 0.1778 0.2794)
							(mid 0.249642 0.249642)
							(end 0.2794 0.1778)
						)
						(arc
							(start 0.2794 -0.1778)
							(mid 0.249642 -0.249642)
							(end 0.1778 -0.2794)
						)
					)
					(width 0)
					(fill yes)
				)
			)
		)
		(pad "2" smd custom
			(at 0 0.4445)
			(size 0.1397 0.1397)
			(layers "F.Cu" "F.Mask" "F.Paste")
			(net "MB0_CM_UV_R")
			(options
				(clearance outline)
				(anchor circle)
			)
			(primitives
				(gr_poly
					(pts
						(arc
							(start -0.1778 -0.2794)
							(mid -0.249642 -0.249642)
							(end -0.2794 -0.1778)
						)
						(arc
							(start -0.2794 0.1778)
							(mid -0.249642 0.249642)
							(end -0.1778 0.2794)
						)
						(arc
							(start 0.1778 0.2794)
							(mid 0.249642 0.249642)
							(end 0.2794 0.1778)
						)
						(arc
							(start 0.2794 -0.1778)
							(mid 0.249642 -0.249642)
							(end 0.1778 -0.2794)
						)
					)
					(width 0)
					(fill yes)
				)
			)
		)
	)
	(footprint ""
		(layer "F.Cu")
		(at 305.308 -153.797 -90)
		(property "Reference" "R7888"
			(at 0 0 270)
			(layer "F.SilkS")
			(hide yes)
			(effects
				(font
					(size 1.27 1.27)
				)
			)
		)
		(property "Value" "47R2F-GP"
			(at 0.064008 -3.993896 270)
			(unlocked yes)
			(layer "F.Fab")
			(hide yes)
			(effects
				(font
					(size 1.016 1.016)
					(thickness 0.1524)
				)
			)
		)
		(property "Device Type" "R402H16"
			(at 0.064008 -5.517896 270)
			(unlocked yes)
			(layer "F.Fab")
			(hide yes)
			(effects
				(font
					(size 1.016 1.016)
					(thickness 0.1524)
				)
			)
		)
		(duplicate_pad_numbers_are_jumpers no)
		(fp_line
			(start -0.508 -0.9398)
			(end -0.508 0.9398)
			(stroke
				(width 0.1524)
				(type default)
			)
			(layer "F.SilkS")
		)
		(fp_line
			(start 0.508 -0.9398)
			(end -0.508 -0.9398)
			(stroke
				(width 0.1524)
				(type default)
			)
			(layer "F.SilkS")
		)
		(fp_rect
			(start -0.508 0.9398)
			(end 0.508 -0.9398)
			(stroke
				(width 0)
				(type default)
			)
			(fill no)
			(layer "F.CrtYd")
		)
		(fp_rect
			(start -0.508 0.9398)
			(end 0.508 -0.9398)
			(stroke
				(width 0)
				(type default)
			)
			(fill no)
			(layer "F.Fab")
		)
		(pad "1" smd custom
			(at 0 -0.4445 270)
			(size 0.1397 0.1397)
			(layers "F.Cu" "F.Mask" "F.Paste")
			(net "125_GTX")
			(options
				(clearance outline)
				(anchor circle)
			)
			(primitives
				(gr_poly
					(pts
						(arc
							(start -0.1778 -0.2794)
							(mid -0.249642 -0.249642)
							(end -0.2794 -0.1778)
						)
						(arc
							(start -0.2794 0.1778)
							(mid -0.249642 0.249642)
							(end -0.1778 0.2794)
						)
						(arc
							(start 0.1778 0.2794)
							(mid 0.249642 0.249642)
							(end 0.2794 0.1778)
						)
						(arc
							(start 0.2794 -0.1778)
							(mid 0.249642 -0.249642)
							(end 0.1778 -0.2794)
						)
					)
					(width 0)
					(fill yes)
				)
			)
		)
		(pad "2" smd custom
			(at 0 0.4445 270)
			(size 0.1397 0.1397)
			(layers "F.Cu" "F.Mask" "F.Paste")
			(net "BMC_MAC2_RGMIICK")
			(options
				(clearance outline)
				(anchor circle)
			)
			(primitives
				(gr_poly
					(pts
						(arc
							(start -0.1778 -0.2794)
							(mid -0.249642 -0.249642)
							(end -0.2794 -0.1778)
						)
						(arc
							(start -0.2794 0.1778)
							(mid -0.249642 0.249642)
							(end -0.1778 0.2794)
						)
						(arc
							(start 0.1778 0.2794)
							(mid 0.249642 0.249642)
							(end 0.2794 0.1778)
						)
						(arc
							(start 0.2794 -0.1778)
							(mid 0.249642 -0.249642)
							(end 0.1778 -0.2794)
						)
					)
					(width 0)
					(fill yes)
				)
			)
		)
	)
	(footprint ""
		(layer "F.Cu")
		(at 94.361 -221.361)
		(property "Reference" "SR314"
			(at 0 0 0)
			(layer "F.SilkS")
			(hide yes)
			(effects
				(font
					(size 1.27 1.27)
				)
			)
		)
		(property "Value" "0R2J-2-GP"
			(at 0.064008 -3.993896 0)
			(unlocked yes)
			(layer "F.Fab")
			(hide yes)
			(effects
				(font
					(size 1.016 1.016)
					(thickness 0.1524)
				)
			)
		)
		(property "Device Type" "R402H16"
			(at 0.064008 -5.517896 0)
			(unlocked yes)
			(layer "F.Fab")
			(hide yes)
			(effects
				(font
					(size 1.016 1.016)
					(thickness 0.1524)
				)
			)
		)
		(duplicate_pad_numbers_are_jumpers no)
		(fp_line
			(start -0.508 -0.9398)
			(end -0.508 0.9398)
			(stroke
				(width 0.1524)
				(type default)
			)
			(layer "F.SilkS")
		)
		(fp_line
			(start 0.508 -0.9398)
			(end -0.508 -0.9398)
			(stroke
				(width 0.1524)
				(type default)
			)
			(layer "F.SilkS")
		)
		(fp_rect
			(start -0.508 0.9398)
			(end 0.508 -0.9398)
			(stroke
				(width 0)
				(type default)
			)
			(fill no)
			(layer "F.CrtYd")
		)
		(fp_rect
			(start -0.508 0.9398)
			(end 0.508 -0.9398)
			(stroke
				(width 0)
				(type default)
			)
			(fill no)
			(layer "F.Fab")
		)
		(pad "1" smd custom
			(at 0 -0.4445)
			(size 0.1397 0.1397)
			(layers "F.Cu" "F.Mask" "F.Paste")
			(net "FAULT_SDA")
			(options
				(clearance outline)
				(anchor circle)
			)
			(primitives
				(gr_poly
					(pts
						(arc
							(start -0.1778 -0.2794)
							(mid -0.249642 -0.249642)
							(end -0.2794 -0.1778)
						)
						(arc
							(start -0.2794 0.1778)
							(mid -0.249642 0.249642)
							(end -0.1778 0.2794)
						)
						(arc
							(start 0.1778 0.2794)
							(mid 0.249642 0.249642)
							(end 0.2794 0.1778)
						)
						(arc
							(start 0.2794 -0.1778)
							(mid 0.249642 -0.249642)
							(end 0.1778 -0.2794)
						)
					)
					(width 0)
					(fill yes)
				)
			)
		)
		(pad "2" smd custom
			(at 0 0.4445)
			(size 0.1397 0.1397)
			(layers "F.Cu" "F.Mask" "F.Paste")
			(net "BMC_I2C_SDA_10")
			(options
				(clearance outline)
				(anchor circle)
			)
			(primitives
				(gr_poly
					(pts
						(arc
							(start -0.1778 -0.2794)
							(mid -0.249642 -0.249642)
							(end -0.2794 -0.1778)
						)
						(arc
							(start -0.2794 0.1778)
							(mid -0.249642 0.249642)
							(end -0.1778 0.2794)
						)
						(arc
							(start 0.1778 0.2794)
							(mid 0.249642 0.249642)
							(end 0.2794 0.1778)
						)
						(arc
							(start 0.2794 -0.1778)
							(mid 0.249642 -0.249642)
							(end 0.1778 -0.2794)
						)
					)
					(width 0)
					(fill yes)
				)
			)
		)
	)
	(footprint ""
		(layer "F.Cu")
		(at 297.688 -191.897)
		(property "Reference" "R670"
			(at 0 0 0)
			(layer "F.SilkS")
			(hide yes)
			(effects
				(font
					(size 1.27 1.27)
				)
			)
		)
		(property "Value" "0R2J-2-GP"
			(at 0.064008 -3.993896 0)
			(unlocked yes)
			(layer "F.Fab")
			(hide yes)
			(effects
				(font
					(size 1.016 1.016)
					(thickness 0.1524)
				)
			)
		)
		(property "Device Type" "R402H16"
			(at 0.064008 -5.517896 0)
			(unlocked yes)
			(layer "F.Fab")
			(hide yes)
			(effects
				(font
					(size 1.016 1.016)
					(thickness 0.1524)
				)
			)
		)
		(duplicate_pad_numbers_are_jumpers no)
		(fp_line
			(start -0.508 -0.9398)
			(end -0.508 0.9398)
			(stroke
				(width 0.1524)
				(type default)
			)
			(layer "F.SilkS")
		)
		(fp_line
			(start 0.508 -0.9398)
			(end -0.508 -0.9398)
			(stroke
				(width 0.1524)
				(type default)
			)
			(layer "F.SilkS")
		)
		(fp_rect
			(start -0.508 0.9398)
			(end 0.508 -0.9398)
			(stroke
				(width 0)
				(type default)
			)
			(fill no)
			(layer "F.CrtYd")
		)
		(fp_rect
			(start -0.508 0.9398)
			(end 0.508 -0.9398)
			(stroke
				(width 0)
				(type default)
			)
			(fill no)
			(layer "F.Fab")
		)
		(pad "1" smd custom
			(at 0 -0.4445)
			(size 0.1397 0.1397)
			(layers "F.Cu" "F.Mask" "F.Paste")
			(net "BMC_ENCLOSURE_LED")
			(options
				(clearance outline)
				(anchor circle)
			)
			(primitives
				(gr_poly
					(pts
						(arc
							(start -0.1778 -0.2794)
							(mid -0.249642 -0.249642)
							(end -0.2794 -0.1778)
						)
						(arc
							(start -0.2794 0.1778)
							(mid -0.249642 0.249642)
							(end -0.1778 0.2794)
						)
						(arc
							(start 0.1778 0.2794)
							(mid 0.249642 0.249642)
							(end 0.2794 0.1778)
						)
						(arc
							(start 0.2794 -0.1778)
							(mid 0.249642 -0.249642)
							(end 0.1778 -0.2794)
						)
					)
					(width 0)
					(fill yes)
				)
			)
		)
		(pad "2" smd custom
			(at 0 0.4445)
			(size 0.1397 0.1397)
			(layers "F.Cu" "F.Mask" "F.Paste")
			(net "BMC0_TACH15")
			(options
				(clearance outline)
				(anchor circle)
			)
			(primitives
				(gr_poly
					(pts
						(arc
							(start -0.1778 -0.2794)
							(mid -0.249642 -0.249642)
							(end -0.2794 -0.1778)
						)
						(arc
							(start -0.2794 0.1778)
							(mid -0.249642 0.249642)
							(end -0.1778 0.2794)
						)
						(arc
							(start 0.1778 0.2794)
							(mid 0.249642 0.249642)
							(end 0.2794 0.1778)
						)
						(arc
							(start 0.2794 -0.1778)
							(mid 0.249642 -0.249642)
							(end 0.1778 -0.2794)
						)
					)
					(width 0)
					(fill yes)
				)
			)
		)
	)
	(footprint ""
		(layer "F.Cu")
		(at 274.240752 -190.940436 180)
		(property "Reference" "R317"
			(at 0 0 180)
			(layer "F.SilkS")
			(hide yes)
			(effects
				(font
					(size 1.27 1.27)
				)
			)
		)
		(property "Value" "8K2R2J-3-GP"
			(at 0.064008 -3.993896 180)
			(unlocked yes)
			(layer "F.Fab")
			(hide yes)
			(effects
				(font
					(size 1.016 1.016)
					(thickness 0.1524)
				)
			)
		)
		(property "Device Type" "R402H16"
			(at 0.064008 -5.517896 180)
			(unlocked yes)
			(layer "F.Fab")
			(hide yes)
			(effects
				(font
					(size 1.016 1.016)
					(thickness 0.1524)
				)
			)
		)
		(duplicate_pad_numbers_are_jumpers no)
		(fp_line
			(start 0.508 -0.9398)
			(end -0.508 -0.9398)
			(stroke
				(width 0.1524)
				(type default)
			)
			(layer "F.SilkS")
		)
		(fp_line
			(start -0.508 -0.9398)
			(end -0.508 0.9398)
			(stroke
				(width 0.1524)
				(type default)
			)
			(layer "F.SilkS")
		)
		(fp_rect
			(start -0.508 0.9398)
			(end 0.508 -0.9398)
			(stroke
				(width 0)
				(type default)
			)
			(fill no)
			(layer "F.CrtYd")
		)
		(fp_rect
			(start -0.508 0.9398)
			(end 0.508 -0.9398)
			(stroke
				(width 0)
				(type default)
			)
			(fill no)
			(layer "F.Fab")
		)
		(pad "1" smd custom
			(at 0 -0.4445 180)
			(size 0.1397 0.1397)
			(layers "F.Cu" "F.Mask" "F.Paste")
			(net "PD_USB2VRES")
			(options
				(clearance outline)
				(anchor circle)
			)
			(primitives
				(gr_poly
					(pts
						(arc
							(start -0.1778 -0.2794)
							(mid -0.249642 -0.249642)
							(end -0.2794 -0.1778)
						)
						(arc
							(start -0.2794 0.1778)
							(mid -0.249642 0.249642)
							(end -0.1778 0.2794)
						)
						(arc
							(start 0.1778 0.2794)
							(mid 0.249642 0.249642)
							(end 0.2794 0.1778)
						)
						(arc
							(start 0.2794 -0.1778)
							(mid 0.249642 -0.249642)
							(end 0.1778 -0.2794)
						)
					)
					(width 0)
					(fill yes)
				)
			)
		)
		(pad "2" smd custom
			(at 0 0.4445 180)
			(size 0.1397 0.1397)
			(layers "F.Cu" "F.Mask" "F.Paste")
			(net "GND")
			(options
				(clearance outline)
				(anchor circle)
			)
			(primitives
				(gr_poly
					(pts
						(arc
							(start -0.1778 -0.2794)
							(mid -0.249642 -0.249642)
							(end -0.2794 -0.1778)
						)
						(arc
							(start -0.2794 0.1778)
							(mid -0.249642 0.249642)
							(end -0.1778 0.2794)
						)
						(arc
							(start 0.1778 0.2794)
							(mid 0.249642 0.249642)
							(end 0.2794 0.1778)
						)
						(arc
							(start 0.2794 -0.1778)
							(mid 0.249642 -0.249642)
							(end 0.1778 -0.2794)
						)
					)
					(width 0)
					(fill yes)
				)
			)
		)
	)
	(footprint ""
		(layer "F.Cu")
		(at 59.817 -225.933 180)
		(property "Reference" "PQ33"
			(at 0 0 180)
			(layer "F.SilkS")
			(hide yes)
			(effects
				(font
					(size 1.27 1.27)
				)
			)
		)
		(property "Value" "NST3904F3T5G-GP-U"
			(at -9.8552 -5.2451 180)
			(unlocked yes)
			(layer "F.Fab")
			(hide yes)
			(effects
				(font
					(size 1.016 1.016)
					(thickness 0.1524)
				)
			)
		)
		(property "Device Type" "SOT-1123CBE1006H16"
			(at -9.8552 -6.7691 180)
			(unlocked yes)
			(layer "F.Fab")
			(hide yes)
			(effects
				(font
					(size 1.016 1.016)
					(thickness 0.1524)
				)
			)
		)
		(duplicate_pad_numbers_are_jumpers no)
		(fp_line
			(start 0.6096 0.889)
			(end -0.6096 0.889)
			(stroke
				(width 0.1524)
				(type default)
			)
			(layer "F.SilkS")
		)
		(fp_line
			(start 0.6096 -0.8636)
			(end 0.6096 0.889)
			(stroke
				(width 0.1524)
				(type default)
			)
			(layer "F.SilkS")
		)
		(fp_line
			(start -0.6096 0.889)
			(end -0.6096 -0.8636)
			(stroke
				(width 0.1524)
				(type default)
			)
			(layer "F.SilkS")
		)
		(fp_line
			(start -0.6096 -0.8636)
			(end 0.6096 -0.8636)
			(stroke
				(width 0.1524)
				(type default)
			)
			(layer "F.SilkS")
		)
		(fp_rect
			(start -0.3048 0.4953)
			(end 0.3048 -0.4953)
			(stroke
				(width 0)
				(type default)
			)
			(fill no)
			(layer "F.CrtYd")
		)
		(fp_poly
			(pts
				(xy -0.8636 1.143) (xy -0.8636 -1.1176) (xy 0.8636 -1.1176) (xy 0.8636 -0.00635) (xy 0.3048 -0.00635)
				(xy 0.3048 -0.4953) (xy -0.3048 -0.4953) (xy -0.3048 0.4953) (xy 0.3048 0.4953) (xy 0.3048 0.00635)
				(xy 0.8636 0.00635) (xy 0.8636 1.143)
			)
			(stroke
				(width 0)
				(type default)
			)
			(fill no)
			(layer "F.CrtYd")
		)
		(fp_rect
			(start -0.8636 1.143)
			(end 0.8636 -1.1176)
			(stroke
				(width 0)
				(type default)
			)
			(fill no)
			(layer "F.Fab")
		)
		(pad "B" smd rect
			(at -0.225044 0.450088 180)
			(size 0.254 0.3556)
			(layers "F.Cu" "F.Mask" "F.Paste")
			(net "MB0_TEMP")
		)
		(pad "C" smd rect
			(at 0 -0.450088 180)
			(size 0.4064 0.3048)
			(layers "F.Cu" "F.Mask" "F.Paste")
			(net "MB0_TEMP")
		)
		(pad "E" smd rect
			(at 0.225044 0.450088 180)
			(size 0.254 0.3556)
			(layers "F.Cu" "F.Mask" "F.Paste")
			(net "GND")
		)
	)
)
